(kicad_pcb
	(version 20241229)
	(generator "pcbnew")
	(generator_version "9.0")
	(general
		(thickness 1.552)
		(legacy_teardrops no)
	)
	(paper "A4")
	(title_block
		(date "2023-07-25")
		(rev "1.1.4")
		(comment 9 "footprints 341-344 of 379")
	)
	(layers
		(0 "F.Cu" signal)
		(4 "In1.Cu" signal)
		(6 "In2.Cu" signal)
		(8 "In3.Cu" signal)
		(10 "In4.Cu" signal)
		(12 "In5.Cu" signal)
		(14 "In6.Cu" signal)
		(2 "B.Cu" signal)
		(9 "F.Adhes" user "F.Adhesive")
		(11 "B.Adhes" user "B.Adhesive")
		(13 "F.Paste" user)
		(15 "B.Paste" user)
		(5 "F.SilkS" user "F.Silkscreen")
		(7 "B.SilkS" user "B.Silkscreen")
		(1 "F.Mask" user)
		(3 "B.Mask" user)
		(17 "Dwgs.User" user "User.Drawings")
		(19 "Cmts.User" user "User.Comments")
		(21 "Eco1.User" user "User.Eco1")
		(23 "Eco2.User" user "User.Eco2")
		(25 "Edge.Cuts" user)
		(27 "Margin" user)
		(31 "F.CrtYd" user "F.Courtyard")
		(29 "B.CrtYd" user "B.Courtyard")
		(35 "F.Fab" user)
		(33 "B.Fab" user)
	)
	(footprint "antmicro-footprints:SOT-23-3"
		(layer "B.Cu")
		(at 158.63 68.35 -90)
		(property "Reference" "Q1"
			(at -1.01 -2.9 180)
			(layer "B.SilkS")
			(effects
				(font
					(size 0.65 0.65)
					(thickness 0.15)
				)
				(justify left bottom mirror)
			)
		)
		(property "Value" "2N7002_SOT-23-3"
			(at -1.9 -2.7 90)
			(layer "B.Fab")
			(hide yes)
			(effects
				(font
					(size 0.7 0.7)
					(thickness 0.15)
				)
				(justify left bottom mirror)
			)
		)
		(property "Datasheet" "https://www.onsemi.com/pub/Collateral/NDS7002A-D.PDF"
			(at 0 0 270)
			(layer "F.Fab")
			(hide yes)
			(effects
				(font
					(size 1.27 1.27)
					(thickness 0.15)
				)
			)
		)
		(property "Description" "Power MOSFET, N Channel, 60 V, 115 mA, 1.2 ohm, SOT-23, Surface Mount"
			(at 0 0 270)
			(layer "F.Fab")
			(hide yes)
			(effects
				(font
					(size 1.27 1.27)
					(thickness 0.15)
				)
			)
		)
		(property "Author" "Antmicro"
			(at 90.28 226.98 0)
			(layer "B.Fab")
			(hide yes)
			(effects
				(font
					(size 1 1)
					(thickness 0.15)
				)
				(justify mirror)
			)
		)
		(property "License" "Apache-2.0"
			(at 90.28 226.98 0)
			(layer "B.Fab")
			(hide yes)
			(effects
				(font
					(size 1 1)
					(thickness 0.15)
				)
				(justify mirror)
			)
		)
		(property "MPN" "2N7002"
			(at 90.28 226.98 0)
			(layer "B.Fab")
			(hide yes)
			(effects
				(font
					(size 1 1)
					(thickness 0.15)
				)
				(justify mirror)
			)
		)
		(property "Manufacturer" "ON Semiconductor"
			(at 90.28 226.98 0)
			(layer "B.Fab")
			(hide yes)
			(effects
				(font
					(size 1 1)
					(thickness 0.15)
				)
				(justify mirror)
			)
		)
		(sheetname "/Power Supply/")
		(sheetfile "supply.kicad_sch")
		(attr smd)
		(fp_line
			(start 0.7 1.5)
			(end -0.7 1.5)
			(stroke
				(width 0.15)
				(type solid)
			)
			(layer "B.SilkS")
		)
		(fp_line
			(start -1.45 1.35)
			(end -0.85 1.35)
			(stroke
				(width 0.15)
				(type solid)
			)
			(layer "B.SilkS")
		)
		(fp_line
			(start -0.85 1.35)
			(end -0.7 1.5)
			(stroke
				(width 0.15)
				(type solid)
			)
			(layer "B.SilkS")
		)
		(fp_line
			(start 0.7 0.4)
			(end 0.7 1.5)
			(stroke
				(width 0.15)
				(type solid)
			)
			(layer "B.SilkS")
		)
		(fp_line
			(start 0.7 -0.4)
			(end 0.7 -1.5)
			(stroke
				(width 0.15)
				(type solid)
			)
			(layer "B.SilkS")
		)
		(fp_line
			(start -0.7 -1.5)
			(end -0.7 -1.35)
			(stroke
				(width 0.15)
				(type solid)
			)
			(layer "B.SilkS")
		)
		(fp_line
			(start 0.7 -1.5)
			(end -0.7 -1.5)
			(stroke
				(width 0.15)
				(type solid)
			)
			(layer "B.SilkS")
		)
		(fp_line
			(start -0.9 1.6)
			(end 0.825 1.6)
			(stroke
				(width 0.05)
				(type solid)
			)
			(layer "B.CrtYd")
		)
		(fp_line
			(start -0.9 1.6)
			(end -0.9 1.4)
			(stroke
				(width 0.05)
				(type solid)
			)
			(layer "B.CrtYd")
		)
		(fp_line
			(start 0.825 1.6)
			(end 0.825 0.45)
			(stroke
				(width 0.05)
				(type solid)
			)
			(layer "B.CrtYd")
		)
		(fp_line
			(start -0.9 1.4)
			(end -1.75 1.4)
			(stroke
				(width 0.05)
				(type solid)
			)
			(layer "B.CrtYd")
		)
		(fp_line
			(start -1.75 0.5)
			(end -1.75 1.4)
			(stroke
				(width 0.05)
				(type solid)
			)
			(layer "B.CrtYd")
		)
		(fp_line
			(start -0.85 0.5)
			(end -1.75 0.5)
			(stroke
				(width 0.05)
				(type solid)
			)
			(layer "B.CrtYd")
		)
		(fp_line
			(start 0.825 0.45)
			(end 1.75 0.45)
			(stroke
				(width 0.05)
				(type solid)
			)
			(layer "B.CrtYd")
		)
		(fp_line
			(start 1.75 0.45)
			(end 1.75 -0.45)
			(stroke
				(width 0.05)
				(type solid)
			)
			(layer "B.CrtYd")
		)
		(fp_line
			(start 0.85 -0.45)
			(end 0.85 -1.65)
			(stroke
				(width 0.05)
				(type solid)
			)
			(layer "B.CrtYd")
		)
		(fp_line
			(start 1.75 -0.45)
			(end 0.85 -0.45)
			(stroke
				(width 0.05)
				(type solid)
			)
			(layer "B.CrtYd")
		)
		(fp_line
			(start -1.75 -0.5)
			(end -0.85 -0.5)
			(stroke
				(width 0.05)
				(type solid)
			)
			(layer "B.CrtYd")
		)
		(fp_line
			(start -0.85 -0.5)
			(end -0.85 0.5)
			(stroke
				(width 0.05)
				(type solid)
			)
			(layer "B.CrtYd")
		)
		(fp_line
			(start -1.75 -1.4)
			(end -1.75 -0.5)
			(stroke
				(width 0.05)
				(type solid)
			)
			(layer "B.CrtYd")
		)
		(fp_line
			(start -0.85 -1.4)
			(end -1.75 -1.4)
			(stroke
				(width 0.05)
				(type solid)
			)
			(layer "B.CrtYd")
		)
		(fp_line
			(start -0.85 -1.65)
			(end -0.85 -1.4)
			(stroke
				(width 0.05)
				(type solid)
			)
			(layer "B.CrtYd")
		)
		(fp_line
			(start 0.85 -1.65)
			(end -0.85 -1.65)
			(stroke
				(width 0.05)
				(type solid)
			)
			(layer "B.CrtYd")
		)
		(fp_line
			(start -0.437 1.526)
			(end 0.688 1.526)
			(stroke
				(width 0.15)
				(type solid)
			)
			(layer "B.Fab")
		)
		(fp_line
			(start -0.437 1.526)
			(end -0.712 1.325)
			(stroke
				(width 0.15)
				(type solid)
			)
			(layer "B.Fab")
		)
		(fp_line
			(start -0.712 1.325)
			(end -0.712 -1.523)
			(stroke
				(width 0.15)
				(type solid)
			)
			(layer "B.Fab")
		)
		(fp_line
			(start -0.712 -1.519)
			(end 0.688 -1.519)
			(stroke
				(width 0.15)
				(type solid)
			)
			(layer "B.Fab")
		)
		(fp_line
			(start 0.688 -1.519)
			(end 0.688 1.52)
			(stroke
				(width 0.15)
				(type solid)
			)
			(layer "B.Fab")
		)
		(pad "1" smd roundrect
			(at -1.1 0.951 270)
			(size 1 0.6)
			(layers "B.Cu" "B.Mask" "B.Paste")
			(roundrect_rratio 0.15)
			(net 325 "USB_POWER_IN")
			(pinfunction "G")
			(pintype "input")
		)
		(pad "2" smd roundrect
			(at -1.1 -0.949 270)
			(size 1 0.6)
			(layers "B.Cu" "B.Mask" "B.Paste")
			(roundrect_rratio 0.15)
			(net 1 "GND")
			(pinfunction "S")
			(pintype "passive")
		)
		(pad "3" smd roundrect
			(at 1.1 0.0005 270)
			(size 1 0.6)
			(layers "B.Cu" "B.Mask" "B.Paste")
			(roundrect_rratio 0.15)
			(net 259 "Net-(Q1-D)")
			(pinfunction "D")
			(pintype "passive")
		)
	)
	(footprint "antmicro-footprints:C_0201"
		(layer "B.Cu")
		(at 123.65 85.85 -90)
		(descr "Capacitor SMD 0201")
		(tags "capacitor SMD 0201")
		(property "Reference" "C38"
			(at -13.71 9.17 90)
			(layer "B.SilkS")
			(effects
				(font
					(size 0.65 0.65)
					(thickness 0.15)
				)
				(justify left bottom mirror)
			)
		)
		(property "Value" "C_100n_0201"
			(at 0 -1.4 90)
			(layer "B.Fab")
			(hide yes)
			(effects
				(font
					(size 0.7 0.7)
					(thickness 0.15)
				)
				(justify left bottom mirror)
			)
		)
		(property "Datasheet" "https://www.yageo.com/en/Chart/Download/pdf/CC0201KRX6S5BB104"
			(at 0 0 270)
			(layer "F.Fab")
			(hide yes)
			(effects
				(font
					(size 1.27 1.27)
					(thickness 0.15)
				)
			)
		)
		(property "Description" "SMD Multilayer Ceramic Capacitor, 0.1 µF, 6.3 V, 0201 [0603 Metric], ± 10%, X6S, CC Series"
			(at 0 0 270)
			(layer "F.Fab")
			(hide yes)
			(effects
				(font
					(size 1.27 1.27)
					(thickness 0.15)
				)
			)
		)
		(property "Author" "Antmicro"
			(at 37.8 209.5 0)
			(layer "B.Fab")
			(hide yes)
			(effects
				(font
					(size 1 1)
					(thickness 0.15)
				)
				(justify mirror)
			)
		)
		(property "Dielectric" ""
			(at 37.8 209.5 0)
			(layer "B.Fab")
			(hide yes)
			(effects
				(font
					(size 1 1)
					(thickness 0.15)
				)
				(justify mirror)
			)
		)
		(property "License" "Apache-2.0"
			(at 37.8 209.5 0)
			(layer "B.Fab")
			(hide yes)
			(effects
				(font
					(size 1 1)
					(thickness 0.15)
				)
				(justify mirror)
			)
		)
		(property "MPN" "CC0201KRX6S5BB104"
			(at 37.8 209.5 0)
			(layer "B.Fab")
			(hide yes)
			(effects
				(font
					(size 1 1)
					(thickness 0.15)
				)
				(justify mirror)
			)
		)
		(property "Manufacturer" "YAGEO"
			(at 37.8 209.5 0)
			(layer "B.Fab")
			(hide yes)
			(effects
				(font
					(size 1 1)
					(thickness 0.15)
				)
				(justify mirror)
			)
		)
		(property "Val" "100n"
			(at 37.8 209.5 0)
			(layer "B.Fab")
			(hide yes)
			(effects
				(font
					(size 1 1)
					(thickness 0.15)
				)
				(justify mirror)
			)
		)
		(property "Voltage" ""
			(at 37.8 209.5 0)
			(layer "B.Fab")
			(hide yes)
			(effects
				(font
					(size 1 1)
					(thickness 0.15)
				)
				(justify mirror)
			)
		)
		(property "Public" "False"
			(at 0 0 270)
			(unlocked yes)
			(layer "B.Fab")
			(hide yes)
			(effects
				(font
					(size 1 1)
					(thickness 0.15)
				)
				(justify mirror)
			)
		)
		(sheetname "/DDR3/")
		(sheetfile "ddr3.kicad_sch")
		(attr smd)
		(fp_rect
			(start -0.7 0.35)
			(end 0.7 -0.35)
			(stroke
				(width 0.05)
				(type default)
			)
			(fill no)
			(layer "B.CrtYd")
		)
		(fp_rect
			(start 0.3 -0.15)
			(end -0.301 0.149)
			(stroke
				(width 0.15)
				(type solid)
			)
			(fill no)
			(layer "B.Fab")
		)
		(fp_text user "License: Apache-2.0"
			(at -0.72 -4.4 90)
			(layer "B.Fab")
			(effects
				(font
					(size 0.7 0.7)
					(thickness 0.15)
				)
				(justify left bottom mirror)
			)
		)
		(fp_text user "${REFERENCE}"
			(at -0.72 -3.4 90)
			(layer "B.Fab")
			(effects
				(font
					(size 0.7 0.7)
					(thickness 0.15)
				)
				(justify left bottom mirror)
			)
		)
		(fp_text user "Author: Antmicro"
			(at -0.72 -5.4 90)
			(layer "B.Fab")
			(effects
				(font
					(size 0.7 0.7)
					(thickness 0.15)
				)
				(justify left bottom mirror)
			)
		)
		(pad "" smd roundrect
			(at -0.349 0.002 270)
			(size 0.318 0.36)
			(layers "B.Paste")
			(roundrect_rratio 0.25)
		)
		(pad "" smd roundrect
			(at 0.341 0.002 270)
			(size 0.318 0.36)
			(layers "B.Paste")
			(roundrect_rratio 0.25)
		)
		(pad "1" smd roundrect
			(at -0.321 0.002 270)
			(size 0.46 0.4)
			(layers "B.Cu" "B.Mask")
			(roundrect_rratio 0.25)
			(net 5 "Vref")
			(pintype "passive")
		)
		(pad "2" smd roundrect
			(at 0.32 0.002 270)
			(size 0.46 0.4)
			(layers "B.Cu" "B.Mask")
			(roundrect_rratio 0.25)
			(net 248 "+1V5")
			(pintype "passive")
		)
	)
	(footprint "antmicro-footprints:C_0201"
		(layer "B.Cu")
		(at 127.97 85.52 -45)
		(descr "Capacitor SMD 0201")
		(tags "capacitor SMD 0201")
		(property "Reference" "C83"
			(at -16.444289 -2.669849 315)
			(layer "B.SilkS")
			(effects
				(font
					(size 0.65 0.65)
					(thickness 0.15)
				)
				(justify left bottom mirror)
			)
		)
		(property "Value" "C_100n_0201"
			(at 0 -1.399999 135)
			(layer "B.Fab")
			(hide yes)
			(effects
				(font
					(size 0.7 0.7)
					(thickness 0.15)
				)
				(justify left bottom mirror)
			)
		)
		(property "Datasheet" "https://www.yageo.com/en/Chart/Download/pdf/CC0201KRX6S5BB104"
			(at 0 0 315)
			(layer "F.Fab")
			(hide yes)
			(effects
				(font
					(size 1.27 1.27)
					(thickness 0.15)
				)
			)
		)
		(property "Description" "SMD Multilayer Ceramic Capacitor, 0.1 µF, 6.3 V, 0201 [0603 Metric], ± 10%, X6S, CC Series"
			(at 0 0 315)
			(layer "F.Fab")
			(hide yes)
			(effects
				(font
					(size 1.27 1.27)
					(thickness 0.15)
				)
			)
		)
		(property "Author" "Antmicro"
			(at -22.990226 115.536683 0)
			(layer "B.Fab")
			(hide yes)
			(effects
				(font
					(size 1 1)
					(thickness 0.15)
				)
				(justify mirror)
			)
		)
		(property "Dielectric" ""
			(at -22.990226 115.536683 0)
			(layer "B.Fab")
			(hide yes)
			(effects
				(font
					(size 1 1)
					(thickness 0.15)
				)
				(justify mirror)
			)
		)
		(property "License" "Apache-2.0"
			(at -22.990226 115.536683 0)
			(layer "B.Fab")
			(hide yes)
			(effects
				(font
					(size 1 1)
					(thickness 0.15)
				)
				(justify mirror)
			)
		)
		(property "MPN" "CC0201KRX6S5BB104"
			(at -22.990226 115.536683 0)
			(layer "B.Fab")
			(hide yes)
			(effects
				(font
					(size 1 1)
					(thickness 0.15)
				)
				(justify mirror)
			)
		)
		(property "Manufacturer" "YAGEO"
			(at -22.990226 115.536683 0)
			(layer "B.Fab")
			(hide yes)
			(effects
				(font
					(size 1 1)
					(thickness 0.15)
				)
				(justify mirror)
			)
		)
		(property "Val" "100n"
			(at -22.990226 115.536683 0)
			(layer "B.Fab")
			(hide yes)
			(effects
				(font
					(size 1 1)
					(thickness 0.15)
				)
				(justify mirror)
			)
		)
		(property "Voltage" ""
			(at -22.990226 115.536683 0)
			(layer "B.Fab")
			(hide yes)
			(effects
				(font
					(size 1 1)
					(thickness 0.15)
				)
				(justify mirror)
			)
		)
		(property "Public" "False"
			(at 0 0 315)
			(unlocked yes)
			(layer "B.Fab")
			(hide yes)
			(effects
				(font
					(size 1 1)
					(thickness 0.15)
				)
				(justify mirror)
			)
		)
		(sheetname "/Peripherals/")
		(sheetfile "peripherals.kicad_sch")
		(attr smd)
		(fp_poly
			(pts
				(xy -0.7 0.35) (xy 0.7 0.35) (xy 0.7 -0.35) (xy -0.7 -0.35)
			)
			(stroke
				(width 0.05)
				(type default)
			)
			(fill no)
			(layer "B.CrtYd")
		)
		(fp_poly
			(pts
				(xy 0.3 -0.15) (xy -0.301 -0.15) (xy -0.301 0.149) (xy 0.3 0.149)
			)
			(stroke
				(width 0.15)
				(type solid)
			)
			(fill no)
			(layer "B.Fab")
		)
		(fp_text user "License: Apache-2.0"
			(at -0.72 -4.4 135)
			(layer "B.Fab")
			(effects
				(font
					(size 0.7 0.7)
					(thickness 0.15)
				)
				(justify left bottom mirror)
			)
		)
		(fp_text user "Author: Antmicro"
			(at -0.72 -5.400001 135)
			(layer "B.Fab")
			(effects
				(font
					(size 0.7 0.7)
					(thickness 0.15)
				)
				(justify left bottom mirror)
			)
		)
		(fp_text user "${REFERENCE}"
			(at -0.72 -3.4 135)
			(layer "B.Fab")
			(effects
				(font
					(size 0.7 0.7)
					(thickness 0.15)
				)
				(justify left bottom mirror)
			)
		)
		(pad "" smd roundrect
			(at -0.349 0.002 315)
			(size 0.318 0.36)
			(layers "B.Paste")
			(roundrect_rratio 0.25)
		)
		(pad "" smd roundrect
			(at 0.341 0.002 315)
			(size 0.318 0.36)
			(layers "B.Paste")
			(roundrect_rratio 0.25)
		)
		(pad "1" smd roundrect
			(at -0.321 0.002 315)
			(size 0.46 0.4)
			(layers "B.Cu" "B.Mask")
			(roundrect_rratio 0.25)
			(net 1 "GND")
			(pintype "passive")
		)
		(pad "2" smd roundrect
			(at 0.32 0.002 315)
			(size 0.46 0.4)
			(layers "B.Cu" "B.Mask")
			(roundrect_rratio 0.25)
			(net 3 "+1V2")
			(pintype "passive")
		)
	)
	(footprint "antmicro-footprints:C_0402_1005Metric"
		(layer "B.Cu")
		(at 128.58 62.02 90)
		(descr "Capacitor SMD 0402")
		(tags "capacitor SMD 0402")
		(property "Reference" "C45"
			(at -2.92 0.35 90)
			(layer "B.SilkS")
			(effects
				(font
					(size 0.65 0.65)
					(thickness 0.15)
				)
				(justify right bottom mirror)
			)
		)
		(property "Value" "C_100n_0402"
			(at 0 -1.4 90)
			(layer "B.Fab")
			(hide yes)
			(effects
				(font
					(size 0.7 0.7)
					(thickness 0.15)
				)
				(justify right bottom mirror)
			)
		)
		(property "Datasheet" "https://www.murata.com/products/productdetail?partno=GRM155R61H104KE14%23"
			(at 0 0 90)
			(layer "F.Fab")
			(hide yes)
			(effects
				(font
					(size 1.27 1.27)
					(thickness 0.15)
				)
			)
		)
		(property "Description" "SMD Multilayer Ceramic Capacitor, 0.1 µF, 50 V, 0402 [1005 Metric], ± 10%, X5R, GRM Series"
			(at 0 0 90)
			(layer "F.Fab")
			(hide yes)
			(effects
				(font
					(size 1.27 1.27)
					(thickness 0.15)
				)
			)
		)
		(property "Author" "Antmicro"
			(at 190.6 -66.56 0)
			(layer "B.Fab")
			(hide yes)
			(effects
				(font
					(size 1 1)
					(thickness 0.15)
				)
				(justify mirror)
			)
		)
		(property "Dielectric" "X5R"
			(at 190.6 -66.56 0)
			(layer "B.Fab")
			(hide yes)
			(effects
				(font
					(size 1 1)
					(thickness 0.15)
				)
				(justify mirror)
			)
		)
		(property "License" "Apache-2.0"
			(at 190.6 -66.56 0)
			(layer "B.Fab")
			(hide yes)
			(effects
				(font
					(size 1 1)
					(thickness 0.15)
				)
				(justify mirror)
			)
		)
		(property "MPN" "GRM155R61H104KE14D"
			(at 190.6 -66.56 0)
			(layer "B.Fab")
			(hide yes)
			(effects
				(font
					(size 1 1)
					(thickness 0.15)
				)
				(justify mirror)
			)
		)
		(property "Manufacturer" "Murata"
			(at 190.6 -66.56 0)
			(layer "B.Fab")
			(hide yes)
			(effects
				(font
					(size 1 1)
					(thickness 0.15)
				)
				(justify mirror)
			)
		)
		(property "Val" "100n"
			(at 190.6 -66.56 0)
			(layer "B.Fab")
			(hide yes)
			(effects
				(font
					(size 1 1)
					(thickness 0.15)
				)
				(justify mirror)
			)
		)
		(property "Voltage" "50V"
			(at 190.6 -66.56 0)
			(layer "B.Fab")
			(hide yes)
			(effects
				(font
					(size 1 1)
					(thickness 0.15)
				)
				(justify mirror)
			)
		)
		(sheetname "/DDR3/")
		(sheetfile "ddr3.kicad_sch")
		(attr smd)
		(fp_rect
			(start -0.925 0.47)
			(end 0.925 -0.47)
			(stroke
				(width 0.05)
				(type default)
			)
			(fill no)
			(layer "B.CrtYd")
		)
		(fp_line
			(start 0.504 -0.248)
			(end -0.494 -0.248)
			(stroke
				(width 0.15)
				(type solid)
			)
			(layer "B.Fab")
		)
		(fp_line
			(start -0.494 -0.248)
			(end -0.494 0.25)
			(stroke
				(width 0.15)
				(type solid)
			)
			(layer "B.Fab")
		)
		(fp_line
			(start 0.504 0.25)
			(end 0.504 -0.248)
			(stroke
				(width 0.15)
				(type solid)
			)
			(layer "B.Fab")
		)
		(fp_line
			(start -0.494 0.25)
			(end 0.504 0.25)
			(stroke
				(width 0.15)
				(type solid)
			)
			(layer "B.Fab")
		)
		(fp_text user "${REFERENCE}"
			(at -0.939 -4.599 270)
			(layer "B.Fab")
			(effects
				(font
					(size 0.7 0.7)
					(thickness 0.15)
				)
				(justify left bottom mirror)
			)
		)
		(fp_text user "Author: Antmicro"
			(at -0.939 -3.399 270)
			(layer "B.Fab")
			(effects
				(font
					(size 0.7 0.7)
					(thickness 0.15)
				)
				(justify left bottom mirror)
			)
		)
		(fp_text user "License: Apache-2.0"
			(at -0.939 -5.799 270)
			(layer "B.Fab")
			(effects
				(font
					(size 0.7 0.7)
					(thickness 0.15)
				)
				(justify left bottom mirror)
			)
		)
		(pad "1" smd roundrect
			(at -0.48 0 90)
			(size 0.59 0.64)
			(layers "B.Cu" "B.Mask" "B.Paste")
			(roundrect_rratio 0.25)
			(net 1 "GND")
			(pintype "passive")
		)
		(pad "2" smd roundrect
			(at 0.48 0 90)
			(size 0.59 0.64)
			(layers "B.Cu" "B.Mask" "B.Paste")
			(roundrect_rratio 0.25)
			(net 248 "+1V5")
			(pintype "passive")
		)
	)
)
